# TIMECARD (Time Appliance Project (Time Card)) — schematic netlist excerpt (pin names and nets, part order shuffled) for the footprints in the layout excerpt that follows; sources: Cadence DE-HDL packaged netlist, KiCad conversion of R4006-B0001-02_R01.brd

C286  CAPACITOR  0.22UF 25V 10%  pkg SMC_0402R_H022  page 28 : \1\ = XP3R3V_EN ; \2\ = SG
C70  CAPACITOR  0.1UF 25V 10%  pkg SMC_0402R_H022  page 21 : \1\ = XP5R0V_MAC ; \2\ = SG

(kicad_pcb
	(version 20260206)
	(generator "pcbnew")
	(generator_version "10.0")
	(general
		(thickness 1.6)
		(legacy_teardrops no)
	)
	(paper "A4")
	(title_block
		(title "timecard-production-celestica-r4006 — R4006-B0001-02_R01.brd")
		(comment 1 "Time Appliance Project (Time Card) / footprints 894-895 of 1113")
	)
	(layers
		(0 "F.Cu" signal "TOP")
		(4 "In1.Cu" signal "L02_GND1")
		(6 "In2.Cu" signal "L03_SIG1")
		(8 "In3.Cu" signal "L04_GND2")
		(10 "In4.Cu" signal "L05_VCC1")
		(12 "In5.Cu" signal "L06_VCC2")
		(14 "In6.Cu" signal "L07_GND3")
		(16 "In7.Cu" signal "L08_SIG2")
		(18 "In8.Cu" signal "L09_GND4")
		(2 "B.Cu" signal "BOTTOM")
		(9 "F.Adhes" user "F.Adhesive")
		(11 "B.Adhes" user "B.Adhesive")
		(13 "F.Paste" user "Package Geometry/Pastemask Top")
		(15 "B.Paste" user "Package Geometry/Pastemask Bottom")
		(5 "F.SilkS" user "Ref Des/Silkscreen Top")
		(7 "B.SilkS" user "Ref Des/Silkscreen Bottom")
		(1 "F.Mask" user "Board Geometry/Soldermask Top")
		(3 "B.Mask" user "Board Geometry/Soldermask Bottom")
		(17 "Dwgs.User" user "User.Drawings")
		(19 "Cmts.User" user "User.Comments")
		(21 "Eco1.User" user "User.Eco1")
		(23 "Eco2.User" user "User.Eco2")
		(25 "Edge.Cuts" user "Board Geometry/Outline")
		(27 "Margin" user)
		(31 "F.CrtYd" user "Package Geometry/Place Bound Top")
		(29 "B.CrtYd" user "Package Geometry/Place Bound Bottom")
		(35 "F.Fab" user "Ref Des/Assembly Top")
		(33 "B.Fab" user "Ref Des/Assembly Bottom")
	)
	(footprint ""
		(layer "B.Cu")
		(at 70.866 -58.8518 90)
		(property "Reference" "C70"
			(at 2.6162 7.70763 270)
			(unlocked yes)
			(layer "B.SilkS")
			(effects
				(font
					(size 0.7874 0.5842)
					(thickness 0.1524)
				)
				(justify mirror)
			)
		)
		(property "Value" "VAL*"
			(at -0.0762 2.067306 90)
			(unlocked yes)
			(layer "B.Fab")
			(hide yes)
			(effects
				(font
					(size 0.7874 0.5842)
					(thickness 0.1524)
				)
				(justify mirror)
			)
		)
		(property "Tolerance" "TOL*"
			(at -0.0762 3.032506 90)
			(unlocked yes)
			(layer "Cmts.User")
			(hide yes)
			(effects
				(font
					(size 0.7874 0.5842)
					(thickness 0.1524)
				)
				(justify mirror)
			)
		)
		(property "User Part Number" "PARTNUM*"
			(at -0.1016 4.023106 90)
			(unlocked yes)
			(layer "Cmts.User")
			(hide yes)
			(effects
				(font
					(size 0.7874 0.5842)
					(thickness 0.1524)
				)
				(justify mirror)
			)
		)
		(property "Device Type" "CAPACITOR-G105-0B104-EK,0.1UF,A"
			(at -0.0508 1.127506 90)
			(unlocked yes)
			(layer "B.Fab")
			(hide yes)
			(effects
				(font
					(size 0.7874 0.5842)
					(thickness 0.1524)
				)
				(justify mirror)
			)
		)
		(duplicate_pad_numbers_are_jumpers no)
		(fp_line
			(start 1.143 -0.5588)
			(end 1.143 0.5588)
			(stroke
				(width 0.1)
				(type default)
			)
			(layer "B.SilkS")
		)
		(fp_line
			(start -1.143 -0.5588)
			(end 1.143 -0.5588)
			(stroke
				(width 0.1)
				(type default)
			)
			(layer "B.SilkS")
		)
		(fp_line
			(start 1.143 0.5588)
			(end -1.143 0.5588)
			(stroke
				(width 0.1)
				(type default)
			)
			(layer "B.SilkS")
		)
		(fp_line
			(start -1.143 0.5588)
			(end -1.143 -0.5588)
			(stroke
				(width 0.1)
				(type default)
			)
			(layer "B.SilkS")
		)
		(fp_rect
			(start -1.143 -0.5588)
			(end 1.143 0.5588)
			(stroke
				(width 0)
				(type default)
			)
			(fill no)
			(layer "B.CrtYd")
		)
		(fp_line
			(start 0.508 -0.3048)
			(end 0.508 0.3048)
			(stroke
				(width 0.1)
				(type default)
			)
			(layer "B.Fab")
		)
		(fp_line
			(start -0.508 -0.3048)
			(end 0.508 -0.3048)
			(stroke
				(width 0.1)
				(type default)
			)
			(layer "B.Fab")
		)
		(fp_line
			(start 0.508 0.3048)
			(end -0.508 0.3048)
			(stroke
				(width 0.1)
				(type default)
			)
			(layer "B.Fab")
		)
		(fp_line
			(start -0.508 0.3048)
			(end -0.508 -0.3048)
			(stroke
				(width 0.1)
				(type default)
			)
			(layer "B.Fab")
		)
		(pad "1" smd rect
			(at 0.5334 0 270)
			(size 0.7112 0.6096)
			(layers "B.Cu" "B.Mask" "B.Paste")
			(net "XP5R0V_MAC")
		)
		(pad "2" smd rect
			(at -0.5334 0 270)
			(size 0.7112 0.6096)
			(layers "B.Cu" "B.Mask" "B.Paste")
			(net "SG")
		)
		(zone
			(layer "B.Cu")
			(hatch none 0.5)
			(connect_pads
				(clearance 0)
			)
			(min_thickness 0.25)
			(keepout
				(tracks allowed)
				(vias not_allowed)
				(pads allowed)
				(copperpour not_allowed)
				(footprints allowed)
			)
			(placement
				(enabled no)
				(sheetname "")
			)
			(fill
				(thermal_gap 0.5)
				(thermal_bridge_width 0.5)
				(island_removal_mode 0)
			)
			(polygon
				(pts
					(xy 70.5612 -58.7756) (xy 71.1708 -58.7756) (xy 71.1708 -58.928) (xy 70.5612 -58.928)
				)
			)
		)
	)
	(footprint ""
		(layer "B.Cu")
		(at 89.9922 -102.4128 180)
		(property "Reference" "C286"
			(at -3.3528 -0.09017 0)
			(unlocked yes)
			(layer "B.SilkS")
			(effects
				(font
					(size 0.7874 0.5842)
					(thickness 0.1524)
				)
				(justify mirror)
			)
		)
		(property "Value" "VAL*"
			(at -0.0762 2.067306 180)
			(unlocked yes)
			(layer "B.Fab")
			(hide yes)
			(effects
				(font
					(size 0.7874 0.5842)
					(thickness 0.1524)
				)
				(justify mirror)
			)
		)
		(property "Tolerance" "TOL*"
			(at -0.0762 3.032506 180)
			(unlocked yes)
			(layer "Cmts.User")
			(hide yes)
			(effects
				(font
					(size 0.7874 0.5842)
					(thickness 0.1524)
				)
				(justify mirror)
			)
		)
		(property "User Part Number" "PARTNUM*"
			(at -0.1016 4.023106 180)
			(unlocked yes)
			(layer "Cmts.User")
			(hide yes)
			(effects
				(font
					(size 0.7874 0.5842)
					(thickness 0.1524)
				)
				(justify mirror)
			)
		)
		(property "Device Type" "CAPACITOR-G105-0B224-DK,0.22UFA"
			(at -0.0508 1.127506 180)
			(unlocked yes)
			(layer "B.Fab")
			(hide yes)
			(effects
				(font
					(size 0.7874 0.5842)
					(thickness 0.1524)
				)
				(justify mirror)
			)
		)
		(duplicate_pad_numbers_are_jumpers no)
		(fp_line
			(start 1.143 0.5588)
			(end -1.143 0.5588)
			(stroke
				(width 0.1)
				(type default)
			)
			(layer "B.SilkS")
		)
		(fp_line
			(start 1.143 -0.5588)
			(end 1.143 0.5588)
			(stroke
				(width 0.1)
				(type default)
			)
			(layer "B.SilkS")
		)
		(fp_line
			(start -1.143 0.5588)
			(end -1.143 -0.5588)
			(stroke
				(width 0.1)
				(type default)
			)
			(layer "B.SilkS")
		)
		(fp_line
			(start -1.143 -0.5588)
			(end 1.143 -0.5588)
			(stroke
				(width 0.1)
				(type default)
			)
			(layer "B.SilkS")
		)
		(fp_rect
			(start 1.143 -0.5588)
			(end -1.143 0.5588)
			(stroke
				(width 0)
				(type default)
			)
			(fill no)
			(layer "B.CrtYd")
		)
		(fp_line
			(start 0.508 0.3048)
			(end -0.508 0.3048)
			(stroke
				(width 0.1)
				(type default)
			)
			(layer "B.Fab")
		)
		(fp_line
			(start 0.508 -0.3048)
			(end 0.508 0.3048)
			(stroke
				(width 0.1)
				(type default)
			)
			(layer "B.Fab")
		)
		(fp_line
			(start -0.508 0.3048)
			(end -0.508 -0.3048)
			(stroke
				(width 0.1)
				(type default)
			)
			(layer "B.Fab")
		)
		(fp_line
			(start -0.508 -0.3048)
			(end 0.508 -0.3048)
			(stroke
				(width 0.1)
				(type default)
			)
			(layer "B.Fab")
		)
		(pad "1" smd rect
			(at 0.5334 0)
			(size 0.7112 0.6096)
			(layers "B.Cu" "B.Mask" "B.Paste")
			(net "XP3R3V_EN")
		)
		(pad "2" smd rect
			(at -0.5334 0)
			(size 0.7112 0.6096)
			(layers "B.Cu" "B.Mask" "B.Paste")
			(net "SG")
		)
		(zone
			(layer "B.Cu")
			(hatch none 0.5)
			(connect_pads
				(clearance 0)
			)
			(min_thickness 0.25)
			(keepout
				(tracks allowed)
				(vias not_allowed)
				(pads allowed)
				(copperpour not_allowed)
				(footprints allowed)
			)
			(placement
				(enabled no)
				(sheetname "")
			)
			(fill
				(thermal_gap 0.5)
				(thermal_bridge_width 0.5)
				(island_removal_mode 0)
			)
			(polygon
				(pts
					(xy 89.916 -102.108) (xy 90.0684 -102.108) (xy 90.0684 -102.7176) (xy 89.916 -102.7176)
				)
			)
		)
		(zone
			(layer "B.Cu")
			(hatch none 0.5)
			(connect_pads
				(clearance 0)
			)
			(min_thickness 0.25)
			(keepout
				(tracks not_allowed)
				(vias allowed)
				(pads allowed)
				(copperpour not_allowed)
				(footprints allowed)
			)
			(placement
				(enabled no)
				(sheetname "")
			)
			(fill
				(thermal_gap 0.5)
				(thermal_bridge_width 0.5)
				(island_removal_mode 0)
			)
			(polygon
				(pts
					(xy 89.916 -102.108) (xy 90.0684 -102.108) (xy 90.0684 -102.7176) (xy 89.916 -102.7176)
				)
			)
		)
	)
)
